# BASEBOARD_FAB2 (Tioga Pass) — schematic netlist excerpt (pin names and nets, part order shuffled) for the footprints in the layout excerpt that follows; sources: Cadence DE-HDL packaged netlist, KiCad conversion of Wiwynn_Tioga_Pass_MB.brd

J8A1  CONN72_G97614002_A  CONN  pkg CP  page 173
  SIDEBANDA_7  = TP_FM_QAT_CBL_PRSNT0_R_N
  SIDEBANDA_0  = SGPIO_PCH_SATA_CLOCK_R
  GND(23)  = GND
  RXA1_DP  = SATA6G_P1_RX_C_DP
  RXA1_DN  = SATA6G_P1_RX_C_DN
  GND(22)  = GND
  RXA3_DP  = SATA6G_P3_RX_C_DP
  RXA3_DN  = SATA6G_P3_RX_C_DN
  GND(21)  = GND
  SIDEBANDA_3  = GND
  SIDEBANDA_1  = SGPIO_PCH_SATA_LOAD_R
  GND(20)  = GND
  RXA0_DP  = SATA6G_P0_RX_C_DP
  RXA0_DN  = SATA6G_P0_RX_C_DN
  GND(19)  = GND
  RXA2_DP  = SATA6G_P2_RX_C_DP
  RXA2_DN  = SATA6G_P2_RX_C_DN
  GND(18)  = GND
  SIDEBANDA_4  = SGPIO_PCH_SATA_DOUT0_R
  SIDEBANDA_2  = GND
  GND(17)  = GND
  TXA1_DP  = SATA6G_P1_TX_C_DP
  TXA1_DN  = SATA6G_P1_TX_C_DN
  GND(16)  = GND
  TXA3_DP  = SATA6G_P3_TX_C_DP
  TXA3_DN  = SATA6G_P3_TX_C_DN
  GND(15)  = GND
  SIDEBANDA_5  = PU_DATAIN1_SATA_0_R
  SIDEBANDA_6  = PD_SATA0_CONTROLLER_TYPE_R
  GND(14)  = GND
  TXA0_DP  = SATA6G_P0_TX_C_DP
  TXA0_DN  = SATA6G_P0_TX_C_DN
  GND(13)  = GND
  TXA2_DP  = SATA6G_P2_TX_C_DP
  TXA2_DN  = SATA6G_P2_TX_C_DN
  GND(12)  = GND
  SIDEBANDB_7  = TP_FM_QAT_CBL_PRSNT1_N_R
  SIDEBANDB_0  = TP_SGPIO_SATA_CLOCK1_R
  GND(11)  = GND
  RXB1_DP  = SATA6G_P5_RX_C_DP
  RXB1_DN  = SATA6G_P5_RX_C_DN
  GND(10)  = GND
  RXB3_DP  = SATA6G_P7_RX_C_DP
  RXB3_DN  = SATA6G_P7_RX_C_DN
  GND(9)  = GND
  SIDEBANDB_3  = GND
  SIDEBANDB_1  = TP_SGPIO_SATA_LOAD1_R
  GND(8)  = GND
  RXB0_DP  = SATA6G_P4_RX_C_DP
  RXB0_DN  = SATA6G_P4_RX_C_DN
  GND(7)  = GND
  RXB2_DP  = SATA6G_P6_RX_C_DP
  RXB2_DN  = SATA6G_P6_RX_C_DN
  GND(6)  = GND
  SIDEBANDB_4  = TP_SGPIO_SATA_DATA1_R
  SIDEBANDB_2  = GND
  GND(5)  = GND
  TXB1_DP  = SATA6G_P5_TX_C_DP
  TXB1_DN  = SATA6G_P5_TX_C_DN
  GND(4)  = GND
  TXB3_DP  = SATA6G_P7_TX_C_DP
  TXB3_DN  = SATA6G_P7_TX_C_DN
  GND(3)  = GND
  SIDEBANDB_5  = PU_DATAIN1_SATA_1_R
  SIDEBANDB_6  = PD_SATA1_CONTROLLER_TYPE_R
  GND(2)  = GND
  TXB0_DP  = SATA6G_P4_TX_C_DP
  TXB0_DN  = SATA6G_P4_TX_C_DN
  GND(1)  = GND
  TXB2_DP  = SATA6G_P6_TX_C_DP
  TXB2_DN  = SATA6G_P6_TX_C_DN
  GND(0)  = GND

(kicad_pcb
	(version 20260206)
	(generator "pcbnew")
	(generator_version "10.0")
	(general
		(thickness 1.6)
		(legacy_teardrops no)
	)
	(paper "A4")
	(title_block
		(title "Wiwynn_Tioga_Pass_MB.brd")
		(comment 1 "Tioga Pass / footprint 1251 of 4770 (J8A1), pads 1-31 of 77")
	)
	(layers
		(0 "F.Cu" signal "TOP")
		(4 "In1.Cu" signal "L2GND")
		(6 "In2.Cu" signal "L3")
		(8 "In3.Cu" signal "L4GND")
		(10 "In4.Cu" signal "L5")
		(12 "In5.Cu" signal "L6GND")
		(14 "In6.Cu" signal "L7VCC")
		(16 "In7.Cu" signal "L8VCC")
		(18 "In8.Cu" signal "L9GND")
		(20 "In9.Cu" signal "L10")
		(22 "In10.Cu" signal "L11GND")
		(24 "In11.Cu" signal "L12")
		(26 "In12.Cu" signal "L13GND")
		(2 "B.Cu" signal "BOTTOM")
		(9 "F.Adhes" user "F.Adhesive")
		(11 "B.Adhes" user "B.Adhesive")
		(13 "F.Paste" user "Package Geometry/Pastemask Top")
		(15 "B.Paste" user "Package Geometry/Pastemask Bottom")
		(5 "F.SilkS" user "Ref Des/Silkscreen Top")
		(7 "B.SilkS" user "Ref Des/Silkscreen Bottom")
		(1 "F.Mask" user "Board Geometry/Soldermask Top")
		(3 "B.Mask" user "Board Geometry/Soldermask Bottom")
		(17 "Dwgs.User" user "User.Drawings")
		(19 "Cmts.User" user "User.Comments")
		(21 "Eco1.User" user "User.Eco1")
		(23 "Eco2.User" user "User.Eco2")
		(25 "Edge.Cuts" user "Board Geometry/Outline")
		(27 "Margin" user)
		(31 "F.CrtYd" user "Package Geometry/Place Bound Top")
		(29 "B.CrtYd" user "Package Geometry/Place Bound Bottom")
		(35 "F.Fab" user "Ref Des/Assembly Top")
		(33 "B.Fab" user "Ref Des/Assembly Bottom")
	)
	(footprint ""
		(layer "F.Cu")
		(at 430.276 -154.94 -90)
		(property "Reference" "J8A1"
			(at 15.64767 10.287 0)
			(unlocked yes)
			(layer "B.SilkS")
			(effects
				(font
					(size 0.7874 0.5842)
					(thickness 0.1524)
				)
				(justify left mirror)
			)
		)
		(property "Value" ""
			(at 0 0 270)
			(layer "F.Fab")
			(effects
				(font
					(size 1.27 1.27)
				)
			)
		)
		(duplicate_pad_numbers_are_jumpers no)
		(pad "" np_thru_hole circle
			(at -1.329944 -2.990088 270)
			(size 0.254 0.254)
			(drill 2.2098)
			(layers "*.Cu" "*.Mask")
			(clearance 1.2954)
			(thermal_gap 1.2954)
		)
		(pad "" np_thru_hole circle
			(at -1.329944 21.010118 270)
			(size 0.254 0.254)
			(drill 2.2098)
			(layers "*.Cu" "*.Mask")
			(clearance 1.2954)
			(thermal_gap 1.2954)
		)
		(pad "" np_thru_hole circle
			(at 10.700004 -2.990088 270)
			(size 0.254 0.254)
			(drill 2.2098)
			(layers "*.Cu" "*.Mask")
			(clearance 1.2954)
			(thermal_gap 1.2954)
		)
		(pad "" np_thru_hole circle
			(at 10.700004 9.009888 270)
			(size 0.254 0.254)
			(drill 2.2098)
			(layers "*.Cu" "*.Mask")
			(clearance 1.2954)
			(thermal_gap 1.2954)
		)
		(pad "" np_thru_hole circle
			(at 10.700004 21.010118 270)
			(size 0.254 0.254)
			(drill 2.2098)
			(layers "*.Cu" "*.Mask")
			(clearance 1.2954)
			(thermal_gap 1.2954)
		)
		(pad "1A1" thru_hole rect
			(at 0 0 270)
			(size 0.7874 0.7874)
			(drill 0.381)
			(layers "*.Cu" "*.Mask")
			(remove_unused_layers no)
			(net "TP_FM_QAT_CBL_PRSNT0_R_N")
			(clearance 0.1143)
			(thermal_gap 0.1143)
			(padstack
				(mode front_inner_back)
				(layer "Inner"
					(shape circle)
					(size 0.7874 0.7874)
					(clearance 0.1143)
				)
				(layer "B.Cu"
					(shape rect)
					(size 0.7874 0.7874)
					(clearance 0.1143)
				)
			)
		)
		(pad "1A2" thru_hole circle
			(at -1.400048 0.750062 270)
			(size 0.7874 0.7874)
			(drill 0.381)
			(layers "*.Cu" "*.Mask")
			(remove_unused_layers no)
			(net "SGPIO_PCH_SATA_CLOCK_R")
			(clearance 0.1143)
			(thermal_gap 0.1143)
		)
		(pad "1A3" thru_hole circle
			(at -0.700024 1.500124 270)
			(size 0.7874 0.7874)
			(drill 0.381)
			(layers "*.Cu" "*.Mask")
			(remove_unused_layers no)
			(net "GND")
			(clearance 0.1143)
			(thermal_gap 0.1143)
		)
		(pad "1A4" thru_hole circle
			(at 0 2.249932 270)
			(size 0.7874 0.7874)
			(drill 0.381)
			(layers "*.Cu" "*.Mask")
			(remove_unused_layers no)
			(net "SATA6G_P1_RX_C_DP")
			(clearance 0.1143)
			(thermal_gap 0.1143)
		)
		(pad "1A5" thru_hole circle
			(at -1.400048 2.999994 270)
			(size 0.7874 0.7874)
			(drill 0.381)
			(layers "*.Cu" "*.Mask")
			(remove_unused_layers no)
			(net "SATA6G_P1_RX_C_DN")
			(clearance 0.1143)
			(thermal_gap 0.1143)
		)
		(pad "1A6" thru_hole circle
			(at -0.700024 3.750056 270)
			(size 0.7874 0.7874)
			(drill 0.381)
			(layers "*.Cu" "*.Mask")
			(remove_unused_layers no)
			(net "GND")
			(clearance 0.1143)
			(thermal_gap 0.1143)
		)
		(pad "1A7" thru_hole circle
			(at 0 4.500118 270)
			(size 0.7874 0.7874)
			(drill 0.381)
			(layers "*.Cu" "*.Mask")
			(remove_unused_layers no)
			(net "SATA6G_P3_RX_C_DP")
			(clearance 0.1143)
			(thermal_gap 0.1143)
		)
		(pad "1A8" thru_hole circle
			(at -1.400048 5.249926 270)
			(size 0.7874 0.7874)
			(drill 0.381)
			(layers "*.Cu" "*.Mask")
			(remove_unused_layers no)
			(net "SATA6G_P3_RX_C_DN")
			(clearance 0.1143)
			(thermal_gap 0.1143)
		)
		(pad "1A9" thru_hole circle
			(at -0.700024 5.999988 270)
			(size 0.7874 0.7874)
			(drill 0.381)
			(layers "*.Cu" "*.Mask")
			(remove_unused_layers no)
			(net "GND")
			(clearance 0.1143)
			(thermal_gap 0.1143)
		)
		(pad "1B1" thru_hole circle
			(at 3.800094 0 270)
			(size 0.7874 0.7874)
			(drill 0.381)
			(layers "*.Cu" "*.Mask")
			(remove_unused_layers no)
			(net "GND")
			(clearance 0.1143)
			(thermal_gap 0.1143)
		)
		(pad "1B2" thru_hole circle
			(at 2.400046 0.750062 270)
			(size 0.7874 0.7874)
			(drill 0.381)
			(layers "*.Cu" "*.Mask")
			(remove_unused_layers no)
			(net "SGPIO_PCH_SATA_LOAD_R")
			(clearance 0.1143)
			(thermal_gap 0.1143)
		)
		(pad "1B3" thru_hole circle
			(at 3.10007 1.500124 270)
			(size 0.7874 0.7874)
			(drill 0.381)
			(layers "*.Cu" "*.Mask")
			(remove_unused_layers no)
			(net "GND")
			(clearance 0.1143)
			(thermal_gap 0.1143)
		)
		(pad "1B4" thru_hole circle
			(at 3.800094 2.249932 270)
			(size 0.7874 0.7874)
			(drill 0.381)
			(layers "*.Cu" "*.Mask")
			(remove_unused_layers no)
			(net "SATA6G_P0_RX_C_DP")
			(clearance 0.1143)
			(thermal_gap 0.1143)
		)
		(pad "1B5" thru_hole circle
			(at 2.400046 2.999994 270)
			(size 0.7874 0.7874)
			(drill 0.381)
			(layers "*.Cu" "*.Mask")
			(remove_unused_layers no)
			(net "SATA6G_P0_RX_C_DN")
			(clearance 0.1143)
			(thermal_gap 0.1143)
		)
		(pad "1B6" thru_hole circle
			(at 3.10007 3.750056 270)
			(size 0.7874 0.7874)
			(drill 0.381)
			(layers "*.Cu" "*.Mask")
			(remove_unused_layers no)
			(net "GND")
			(clearance 0.1143)
			(thermal_gap 0.1143)
		)
		(pad "1B7" thru_hole circle
			(at 3.800094 4.500118 270)
			(size 0.7874 0.7874)
			(drill 0.381)
			(layers "*.Cu" "*.Mask")
			(remove_unused_layers no)
			(net "SATA6G_P2_RX_C_DP")
			(clearance 0.1143)
			(thermal_gap 0.1143)
		)
		(pad "1B8" thru_hole circle
			(at 2.400046 5.249926 270)
			(size 0.7874 0.7874)
			(drill 0.381)
			(layers "*.Cu" "*.Mask")
			(remove_unused_layers no)
			(net "SATA6G_P2_RX_C_DN")
			(clearance 0.1143)
			(thermal_gap 0.1143)
		)
		(pad "1B9" thru_hole circle
			(at 3.10007 5.999988 270)
			(size 0.7874 0.7874)
			(drill 0.381)
			(layers "*.Cu" "*.Mask")
			(remove_unused_layers no)
			(net "GND")
			(clearance 0.1143)
			(thermal_gap 0.1143)
		)
		(pad "1C1" thru_hole circle
			(at 7.599934 0 270)
			(size 0.7874 0.7874)
			(drill 0.381)
			(layers "*.Cu" "*.Mask")
			(remove_unused_layers no)
			(net "SGPIO_PCH_SATA_DOUT0_R")
			(clearance 0.1143)
			(thermal_gap 0.1143)
		)
		(pad "1C2" thru_hole circle
			(at 6.199886 0.750062 270)
			(size 0.7874 0.7874)
			(drill 0.381)
			(layers "*.Cu" "*.Mask")
			(remove_unused_layers no)
			(net "GND")
			(clearance 0.1143)
			(thermal_gap 0.1143)
		)
		(pad "1C3" thru_hole circle
			(at 6.89991 1.500124 270)
			(size 0.7874 0.7874)
			(drill 0.381)
			(layers "*.Cu" "*.Mask")
			(remove_unused_layers no)
			(net "GND")
			(clearance 0.1143)
			(thermal_gap 0.1143)
		)
		(pad "1C4" thru_hole circle
			(at 7.599934 2.249932 270)
			(size 0.7874 0.7874)
			(drill 0.381)
			(layers "*.Cu" "*.Mask")
			(remove_unused_layers no)
			(net "SATA6G_P1_TX_C_DP")
			(clearance 0.1143)
			(thermal_gap 0.1143)
		)
		(pad "1C5" thru_hole circle
			(at 6.199886 2.999994 270)
			(size 0.7874 0.7874)
			(drill 0.381)
			(layers "*.Cu" "*.Mask")
			(remove_unused_layers no)
			(net "SATA6G_P1_TX_C_DN")
			(clearance 0.1143)
			(thermal_gap 0.1143)
		)
		(pad "1C6" thru_hole circle
			(at 6.89991 3.750056 270)
			(size 0.7874 0.7874)
			(drill 0.381)
			(layers "*.Cu" "*.Mask")
			(remove_unused_layers no)
			(net "GND")
			(clearance 0.1143)
			(thermal_gap 0.1143)
		)
		(pad "1C7" thru_hole circle
			(at 7.599934 4.500118 270)
			(size 0.7874 0.7874)
			(drill 0.381)
			(layers "*.Cu" "*.Mask")
			(remove_unused_layers no)
			(net "SATA6G_P3_TX_C_DP")
			(clearance 0.1143)
			(thermal_gap 0.1143)
		)
		(pad "1C8" thru_hole circle
			(at 6.199886 5.249926 270)
			(size 0.7874 0.7874)
			(drill 0.381)
			(layers "*.Cu" "*.Mask")
			(remove_unused_layers no)
			(net "SATA6G_P3_TX_C_DN")
			(clearance 0.1143)
			(thermal_gap 0.1143)
		)
	)
)
